(kicad_pcb
	(version 20260206)
	(generator "pcbnew")
	(generator_version "10.0")
	(general
		(thickness 1.6)
		(legacy_teardrops no)
	)
	(paper "A4")
	(title_block
		(title "03242023_DA0F0TMBIJ0_F0T_Motherboard_J_brd_V01_OCP.brd")
		(comment 1 "Grand Teton / footprints 1780-1786 of 6105")
	)
	(layers
		(0 "F.Cu" signal "TOP")
		(4 "In1.Cu" signal "GND")
		(6 "In2.Cu" signal "IN1")
		(8 "In3.Cu" signal "GND1")
		(10 "In4.Cu" signal "IN2")
		(12 "In5.Cu" signal "GND2")
		(14 "In6.Cu" signal "IN3")
		(16 "In7.Cu" signal "GND3")
		(18 "In8.Cu" signal "VCC")
		(20 "In9.Cu" signal "VCC1")
		(22 "In10.Cu" signal "GND4")
		(24 "In11.Cu" signal "IN4")
		(26 "In12.Cu" signal "GND5")
		(28 "In13.Cu" signal "IN5")
		(30 "In14.Cu" signal "GND6")
		(32 "In15.Cu" signal "IN6")
		(34 "In16.Cu" signal "GND7")
		(2 "B.Cu" signal "BOTTOM")
		(9 "F.Adhes" user "F.Adhesive")
		(11 "B.Adhes" user "B.Adhesive")
		(13 "F.Paste" user "Package Geometry/Pastemask Top")
		(15 "B.Paste" user "Package Geometry/Pastemask Bottom")
		(5 "F.SilkS" user "Ref Des/Silkscreen Top")
		(7 "B.SilkS" user "Ref Des/Silkscreen Bottom")
		(1 "F.Mask" user "Board Geometry/Soldermask Top")
		(3 "B.Mask" user "Board Geometry/Soldermask Bottom")
		(17 "Dwgs.User" user "User.Drawings")
		(19 "Cmts.User" user "User.Comments")
		(21 "Eco1.User" user "User.Eco1")
		(23 "Eco2.User" user "User.Eco2")
		(25 "Edge.Cuts" user "Board Geometry/Outline")
		(27 "Margin" user)
		(31 "F.CrtYd" user "Package Geometry/Place Bound Top")
		(29 "B.CrtYd" user "Package Geometry/Place Bound Bottom")
		(35 "F.Fab" user "Ref Des/Assembly Top")
		(33 "B.Fab" user "Ref Des/Assembly Bottom")
	)
	(footprint ""
		(layer "F.Cu")
		(at 395.10081 -408.517344 -90)
		(property "Reference" "C885"
			(at 0 0 270)
			(layer "F.SilkS")
			(hide yes)
			(effects
				(font
					(size 1.27 1.27)
				)
			)
		)
		(property "Value" ""
			(at 0 0 270)
			(layer "F.Fab")
			(effects
				(font
					(size 1.27 1.27)
				)
			)
		)
		(duplicate_pad_numbers_are_jumpers no)
		(fp_line
			(start -0.299974 0.150114)
			(end -0.299974 -0.150114)
			(stroke
				(width 0.1)
				(type default)
			)
			(layer "F.Fab")
		)
		(fp_line
			(start 0.299974 0.150114)
			(end -0.299974 0.150114)
			(stroke
				(width 0.1)
				(type default)
			)
			(layer "F.Fab")
		)
		(fp_line
			(start -0.299974 -0.150114)
			(end 0.299974 -0.150114)
			(stroke
				(width 0.1)
				(type default)
			)
			(layer "F.Fab")
		)
		(fp_line
			(start 0.299974 -0.150114)
			(end 0.299974 0.150114)
			(stroke
				(width 0.1)
				(type default)
			)
			(layer "F.Fab")
		)
		(pad "1" smd rect
			(at -0.2667 0 270)
			(size 0.3048 0.381)
			(layers "F.Cu" "F.Mask" "F.Paste")
			(net "P5E_CPU0_PE3_TX_C_DP<8>")
		)
		(pad "2" smd rect
			(at 0.2667 0 270)
			(size 0.3048 0.381)
			(layers "F.Cu" "F.Mask" "F.Paste")
			(net "P5E_CPU0_PE3_TX_DP<8>")
		)
	)
	(footprint ""
		(layer "F.Cu")
		(at 243.084858 -50.138838 90)
		(property "Reference" "C1279"
			(at 0 0 90)
			(layer "F.SilkS")
			(hide yes)
			(effects
				(font
					(size 1.27 1.27)
				)
			)
		)
		(property "Value" ""
			(at 0 0 90)
			(layer "F.Fab")
			(effects
				(font
					(size 1.27 1.27)
				)
			)
		)
		(duplicate_pad_numbers_are_jumpers no)
		(fp_line
			(start 0.7874 -0.4064)
			(end 0.7874 0.4064)
			(stroke
				(width 0.1524)
				(type default)
			)
			(layer "F.SilkS")
		)
		(fp_line
			(start -0.7874 -0.4064)
			(end 0.7874 -0.4064)
			(stroke
				(width 0.1524)
				(type default)
			)
			(layer "F.SilkS")
		)
		(fp_line
			(start 0.7874 0.4064)
			(end -0.7874 0.4064)
			(stroke
				(width 0.1524)
				(type default)
			)
			(layer "F.SilkS")
		)
		(fp_line
			(start -0.7874 0.4064)
			(end -0.7874 -0.4064)
			(stroke
				(width 0.1524)
				(type default)
			)
			(layer "F.SilkS")
		)
		(fp_line
			(start -0.12065 -0.305054)
			(end -0.12065 -0.2794)
			(stroke
				(width 0.1)
				(type default)
			)
			(layer "F.Fab")
		)
		(fp_line
			(start -0.67945 -0.305054)
			(end -0.12065 -0.305054)
			(stroke
				(width 0.1)
				(type default)
			)
			(layer "F.Fab")
		)
		(fp_line
			(start 0.67945 -0.3048)
			(end 0.67945 0.3048)
			(stroke
				(width 0.1)
				(type default)
			)
			(layer "F.Fab")
		)
		(fp_line
			(start 0.12065 -0.3048)
			(end 0.67945 -0.3048)
			(stroke
				(width 0.1)
				(type default)
			)
			(layer "F.Fab")
		)
		(fp_line
			(start 0.12065 -0.2794)
			(end 0.12065 -0.3048)
			(stroke
				(width 0.1)
				(type default)
			)
			(layer "F.Fab")
		)
		(fp_line
			(start -0.12065 -0.2794)
			(end 0.12065 -0.2794)
			(stroke
				(width 0.1)
				(type default)
			)
			(layer "F.Fab")
		)
		(fp_line
			(start 0.120396 0.2794)
			(end -0.12065 0.2794)
			(stroke
				(width 0.1)
				(type default)
			)
			(layer "F.Fab")
		)
		(fp_line
			(start -0.12065 0.2794)
			(end -0.12065 0.3048)
			(stroke
				(width 0.1)
				(type default)
			)
			(layer "F.Fab")
		)
		(fp_line
			(start 0.67945 0.3048)
			(end 0.120396 0.3048)
			(stroke
				(width 0.1)
				(type default)
			)
			(layer "F.Fab")
		)
		(fp_line
			(start 0.120396 0.3048)
			(end 0.120396 0.2794)
			(stroke
				(width 0.1)
				(type default)
			)
			(layer "F.Fab")
		)
		(fp_line
			(start -0.12065 0.3048)
			(end -0.67945 0.3048)
			(stroke
				(width 0.1)
				(type default)
			)
			(layer "F.Fab")
		)
		(fp_line
			(start -0.67945 0.3048)
			(end -0.67945 -0.305054)
			(stroke
				(width 0.1)
				(type default)
			)
			(layer "F.Fab")
		)
		(pad "1" smd circle
			(at -0.40005 0 90)
			(size 0 0)
			(layers "F.Cu" "F.Mask" "F.Paste")
			(net "P12V_E1S_0")
		)
		(pad "2" smd circle
			(at 0.40005 0 90)
			(size 0 0)
			(layers "F.Cu" "F.Mask" "F.Paste")
			(net "GND")
		)
	)
	(footprint ""
		(layer "F.Cu")
		(at 32.761428 -100.602034 180)
		(property "Reference" "C1344"
			(at 0 0 180)
			(layer "F.SilkS")
			(hide yes)
			(effects
				(font
					(size 1.27 1.27)
				)
			)
		)
		(property "Value" ""
			(at 0 0 180)
			(layer "F.Fab")
			(effects
				(font
					(size 1.27 1.27)
				)
			)
		)
		(duplicate_pad_numbers_are_jumpers no)
		(fp_line
			(start 0.7874 0.4064)
			(end -0.7874 0.4064)
			(stroke
				(width 0.1524)
				(type default)
			)
			(layer "F.SilkS")
		)
		(fp_line
			(start 0.7874 -0.4064)
			(end 0.7874 0.4064)
			(stroke
				(width 0.1524)
				(type default)
			)
			(layer "F.SilkS")
		)
		(fp_line
			(start -0.7874 0.4064)
			(end -0.7874 -0.4064)
			(stroke
				(width 0.1524)
				(type default)
			)
			(layer "F.SilkS")
		)
		(fp_line
			(start -0.7874 -0.4064)
			(end 0.7874 -0.4064)
			(stroke
				(width 0.1524)
				(type default)
			)
			(layer "F.SilkS")
		)
		(fp_line
			(start 0.67945 0.3048)
			(end 0.120396 0.3048)
			(stroke
				(width 0.1)
				(type default)
			)
			(layer "F.Fab")
		)
		(fp_line
			(start 0.67945 -0.3048)
			(end 0.67945 0.3048)
			(stroke
				(width 0.1)
				(type default)
			)
			(layer "F.Fab")
		)
		(fp_line
			(start 0.12065 -0.2794)
			(end 0.12065 -0.3048)
			(stroke
				(width 0.1)
				(type default)
			)
			(layer "F.Fab")
		)
		(fp_line
			(start 0.12065 -0.3048)
			(end 0.67945 -0.3048)
			(stroke
				(width 0.1)
				(type default)
			)
			(layer "F.Fab")
		)
		(fp_line
			(start 0.120396 0.3048)
			(end 0.120396 0.2794)
			(stroke
				(width 0.1)
				(type default)
			)
			(layer "F.Fab")
		)
		(fp_line
			(start 0.120396 0.2794)
			(end -0.12065 0.2794)
			(stroke
				(width 0.1)
				(type default)
			)
			(layer "F.Fab")
		)
		(fp_line
			(start -0.12065 0.3048)
			(end -0.67945 0.3048)
			(stroke
				(width 0.1)
				(type default)
			)
			(layer "F.Fab")
		)
		(fp_line
			(start -0.12065 0.2794)
			(end -0.12065 0.3048)
			(stroke
				(width 0.1)
				(type default)
			)
			(layer "F.Fab")
		)
		(fp_line
			(start -0.12065 -0.2794)
			(end 0.12065 -0.2794)
			(stroke
				(width 0.1)
				(type default)
			)
			(layer "F.Fab")
		)
		(fp_line
			(start -0.12065 -0.305054)
			(end -0.12065 -0.2794)
			(stroke
				(width 0.1)
				(type default)
			)
			(layer "F.Fab")
		)
		(fp_line
			(start -0.67945 0.3048)
			(end -0.67945 -0.305054)
			(stroke
				(width 0.1)
				(type default)
			)
			(layer "F.Fab")
		)
		(fp_line
			(start -0.67945 -0.305054)
			(end -0.12065 -0.305054)
			(stroke
				(width 0.1)
				(type default)
			)
			(layer "F.Fab")
		)
		(pad "1" smd circle
			(at -0.40005 0 180)
			(size 0 0)
			(layers "F.Cu" "F.Mask" "F.Paste")
			(net "P12V_AUX_ADC_MAM")
		)
		(pad "2" smd circle
			(at 0.40005 0 180)
			(size 0 0)
			(layers "F.Cu" "F.Mask" "F.Paste")
			(net "GND")
		)
	)
	(footprint ""
		(layer "F.Cu")
		(at 107.28833 -238.162592 -90)
		(property "Reference" "C304"
			(at 0 0 270)
			(layer "F.SilkS")
			(hide yes)
			(effects
				(font
					(size 1.27 1.27)
				)
			)
		)
		(property "Value" ""
			(at 0 0 270)
			(layer "F.Fab")
			(effects
				(font
					(size 1.27 1.27)
				)
			)
		)
		(duplicate_pad_numbers_are_jumpers no)
		(fp_line
			(start -0.7874 0.4064)
			(end -0.7874 -0.4064)
			(stroke
				(width 0.1524)
				(type default)
			)
			(layer "F.SilkS")
		)
		(fp_line
			(start 0.7874 0.4064)
			(end -0.7874 0.4064)
			(stroke
				(width 0.1524)
				(type default)
			)
			(layer "F.SilkS")
		)
		(fp_line
			(start -0.7874 -0.4064)
			(end 0.7874 -0.4064)
			(stroke
				(width 0.1524)
				(type default)
			)
			(layer "F.SilkS")
		)
		(fp_line
			(start 0.7874 -0.4064)
			(end 0.7874 0.4064)
			(stroke
				(width 0.1524)
				(type default)
			)
			(layer "F.SilkS")
		)
		(fp_line
			(start -0.67945 0.3048)
			(end -0.67945 -0.305054)
			(stroke
				(width 0.1)
				(type default)
			)
			(layer "F.Fab")
		)
		(fp_line
			(start -0.12065 0.3048)
			(end -0.67945 0.3048)
			(stroke
				(width 0.1)
				(type default)
			)
			(layer "F.Fab")
		)
		(fp_line
			(start 0.120396 0.3048)
			(end 0.120396 0.2794)
			(stroke
				(width 0.1)
				(type default)
			)
			(layer "F.Fab")
		)
		(fp_line
			(start 0.67945 0.3048)
			(end 0.120396 0.3048)
			(stroke
				(width 0.1)
				(type default)
			)
			(layer "F.Fab")
		)
		(fp_line
			(start -0.12065 0.2794)
			(end -0.12065 0.3048)
			(stroke
				(width 0.1)
				(type default)
			)
			(layer "F.Fab")
		)
		(fp_line
			(start 0.120396 0.2794)
			(end -0.12065 0.2794)
			(stroke
				(width 0.1)
				(type default)
			)
			(layer "F.Fab")
		)
		(fp_line
			(start -0.12065 -0.2794)
			(end 0.12065 -0.2794)
			(stroke
				(width 0.1)
				(type default)
			)
			(layer "F.Fab")
		)
		(fp_line
			(start 0.12065 -0.2794)
			(end 0.12065 -0.3048)
			(stroke
				(width 0.1)
				(type default)
			)
			(layer "F.Fab")
		)
		(fp_line
			(start 0.12065 -0.3048)
			(end 0.67945 -0.3048)
			(stroke
				(width 0.1)
				(type default)
			)
			(layer "F.Fab")
		)
		(fp_line
			(start 0.67945 -0.3048)
			(end 0.67945 0.3048)
			(stroke
				(width 0.1)
				(type default)
			)
			(layer "F.Fab")
		)
		(fp_line
			(start -0.67945 -0.305054)
			(end -0.12065 -0.305054)
			(stroke
				(width 0.1)
				(type default)
			)
			(layer "F.Fab")
		)
		(fp_line
			(start -0.12065 -0.305054)
			(end -0.12065 -0.2794)
			(stroke
				(width 0.1)
				(type default)
			)
			(layer "F.Fab")
		)
		(pad "1" smd circle
			(at -0.40005 0 270)
			(size 0 0)
			(layers "F.Cu" "F.Mask" "F.Paste")
			(net "PVCCIN_CPU1")
		)
		(pad "2" smd circle
			(at 0.40005 0 270)
			(size 0 0)
			(layers "F.Cu" "F.Mask" "F.Paste")
			(net "GND")
		)
	)
	(footprint ""
		(layer "F.Cu")
		(at 20.785582 -428.024036 90)
		(property "Reference" "R3440"
			(at 0 0 90)
			(layer "F.SilkS")
			(hide yes)
			(effects
				(font
					(size 1.27 1.27)
				)
			)
		)
		(property "Value" ""
			(at 0 0 90)
			(layer "F.Fab")
			(effects
				(font
					(size 1.27 1.27)
				)
			)
		)
		(duplicate_pad_numbers_are_jumpers no)
		(fp_line
			(start 0.7874 -0.4064)
			(end 0.7874 0.4064)
			(stroke
				(width 0.1524)
				(type default)
			)
			(layer "F.SilkS")
		)
		(fp_line
			(start -0.7874 -0.4064)
			(end 0.7874 -0.4064)
			(stroke
				(width 0.1524)
				(type default)
			)
			(layer "F.SilkS")
		)
		(fp_line
			(start 0.7874 0.4064)
			(end -0.7874 0.4064)
			(stroke
				(width 0.1524)
				(type default)
			)
			(layer "F.SilkS")
		)
		(fp_line
			(start -0.7874 0.4064)
			(end -0.7874 -0.4064)
			(stroke
				(width 0.1524)
				(type default)
			)
			(layer "F.SilkS")
		)
		(fp_line
			(start -0.12065 -0.305054)
			(end -0.12065 -0.2794)
			(stroke
				(width 0.1)
				(type default)
			)
			(layer "F.Fab")
		)
		(fp_line
			(start -0.67945 -0.305054)
			(end -0.12065 -0.305054)
			(stroke
				(width 0.1)
				(type default)
			)
			(layer "F.Fab")
		)
		(fp_line
			(start 0.67945 -0.3048)
			(end 0.67945 0.3048)
			(stroke
				(width 0.1)
				(type default)
			)
			(layer "F.Fab")
		)
		(fp_line
			(start 0.12065 -0.3048)
			(end 0.67945 -0.3048)
			(stroke
				(width 0.1)
				(type default)
			)
			(layer "F.Fab")
		)
		(fp_line
			(start 0.12065 -0.2794)
			(end 0.12065 -0.3048)
			(stroke
				(width 0.1)
				(type default)
			)
			(layer "F.Fab")
		)
		(fp_line
			(start -0.12065 -0.2794)
			(end 0.12065 -0.2794)
			(stroke
				(width 0.1)
				(type default)
			)
			(layer "F.Fab")
		)
		(fp_line
			(start 0.120396 0.2794)
			(end -0.12065 0.2794)
			(stroke
				(width 0.1)
				(type default)
			)
			(layer "F.Fab")
		)
		(fp_line
			(start -0.12065 0.2794)
			(end -0.12065 0.3048)
			(stroke
				(width 0.1)
				(type default)
			)
			(layer "F.Fab")
		)
		(fp_line
			(start 0.67945 0.3048)
			(end 0.120396 0.3048)
			(stroke
				(width 0.1)
				(type default)
			)
			(layer "F.Fab")
		)
		(fp_line
			(start 0.120396 0.3048)
			(end 0.120396 0.2794)
			(stroke
				(width 0.1)
				(type default)
			)
			(layer "F.Fab")
		)
		(fp_line
			(start -0.12065 0.3048)
			(end -0.67945 0.3048)
			(stroke
				(width 0.1)
				(type default)
			)
			(layer "F.Fab")
		)
		(fp_line
			(start -0.67945 0.3048)
			(end -0.67945 -0.305054)
			(stroke
				(width 0.1)
				(type default)
			)
			(layer "F.Fab")
		)
		(pad "1" smd circle
			(at -0.40005 0 90)
			(size 0 0)
			(layers "F.Cu" "F.Mask" "F.Paste")
			(net "GPU_BASE_ID0")
		)
		(pad "2" smd circle
			(at 0.40005 0 90)
			(size 0 0)
			(layers "F.Cu" "F.Mask" "F.Paste")
			(net "GND")
		)
	)
	(footprint ""
		(layer "F.Cu")
		(at 347.00718 -338.180172 -90)
		(property "Reference" "PC301"
			(at 0 0 270)
			(layer "F.SilkS")
			(hide yes)
			(effects
				(font
					(size 1.27 1.27)
				)
			)
		)
		(property "Value" ""
			(at 0 0 270)
			(layer "F.Fab")
			(effects
				(font
					(size 1.27 1.27)
				)
			)
		)
		(duplicate_pad_numbers_are_jumpers no)
		(fp_line
			(start -0.7874 0.4064)
			(end -0.7874 -0.4064)
			(stroke
				(width 0.1524)
				(type default)
			)
			(layer "F.SilkS")
		)
		(fp_line
			(start 0.7874 0.4064)
			(end -0.7874 0.4064)
			(stroke
				(width 0.1524)
				(type default)
			)
			(layer "F.SilkS")
		)
		(fp_line
			(start -0.7874 -0.4064)
			(end 0.7874 -0.4064)
			(stroke
				(width 0.1524)
				(type default)
			)
			(layer "F.SilkS")
		)
		(fp_line
			(start 0.7874 -0.4064)
			(end 0.7874 0.4064)
			(stroke
				(width 0.1524)
				(type default)
			)
			(layer "F.SilkS")
		)
		(fp_line
			(start -0.67945 0.3048)
			(end -0.67945 -0.305054)
			(stroke
				(width 0.1)
				(type default)
			)
			(layer "F.Fab")
		)
		(fp_line
			(start -0.12065 0.3048)
			(end -0.67945 0.3048)
			(stroke
				(width 0.1)
				(type default)
			)
			(layer "F.Fab")
		)
		(fp_line
			(start 0.120396 0.3048)
			(end 0.120396 0.2794)
			(stroke
				(width 0.1)
				(type default)
			)
			(layer "F.Fab")
		)
		(fp_line
			(start 0.67945 0.3048)
			(end 0.120396 0.3048)
			(stroke
				(width 0.1)
				(type default)
			)
			(layer "F.Fab")
		)
		(fp_line
			(start -0.12065 0.2794)
			(end -0.12065 0.3048)
			(stroke
				(width 0.1)
				(type default)
			)
			(layer "F.Fab")
		)
		(fp_line
			(start 0.120396 0.2794)
			(end -0.12065 0.2794)
			(stroke
				(width 0.1)
				(type default)
			)
			(layer "F.Fab")
		)
		(fp_line
			(start -0.12065 -0.2794)
			(end 0.12065 -0.2794)
			(stroke
				(width 0.1)
				(type default)
			)
			(layer "F.Fab")
		)
		(fp_line
			(start 0.12065 -0.2794)
			(end 0.12065 -0.3048)
			(stroke
				(width 0.1)
				(type default)
			)
			(layer "F.Fab")
		)
		(fp_line
			(start 0.12065 -0.3048)
			(end 0.67945 -0.3048)
			(stroke
				(width 0.1)
				(type default)
			)
			(layer "F.Fab")
		)
		(fp_line
			(start 0.67945 -0.3048)
			(end 0.67945 0.3048)
			(stroke
				(width 0.1)
				(type default)
			)
			(layer "F.Fab")
		)
		(fp_line
			(start -0.67945 -0.305054)
			(end -0.12065 -0.305054)
			(stroke
				(width 0.1)
				(type default)
			)
			(layer "F.Fab")
		)
		(fp_line
			(start -0.12065 -0.305054)
			(end -0.12065 -0.2794)
			(stroke
				(width 0.1)
				(type default)
			)
			(layer "F.Fab")
		)
		(pad "1" smd circle
			(at -0.40005 0 270)
			(size 0 0)
			(layers "F.Cu" "F.Mask" "F.Paste")
			(net "SW_PVCCIN_CPU0_BOOT1_R")
		)
		(pad "2" smd circle
			(at 0.40005 0 270)
			(size 0 0)
			(layers "F.Cu" "F.Mask" "F.Paste")
			(net "SW_PVCCIN_CPU0_BOOTR1")
		)
	)
	(footprint ""
		(layer "F.Cu")
		(at 189.80023 -35.017456 180)
		(property "Reference" "R1854"
			(at 0 0 180)
			(layer "F.SilkS")
			(hide yes)
			(effects
				(font
					(size 1.27 1.27)
				)
			)
		)
		(property "Value" ""
			(at 0 0 180)
			(layer "F.Fab")
			(effects
				(font
					(size 1.27 1.27)
				)
			)
		)
		(duplicate_pad_numbers_are_jumpers no)
		(fp_line
			(start 0.7874 0.4064)
			(end -0.7874 0.4064)
			(stroke
				(width 0.1524)
				(type default)
			)
			(layer "F.SilkS")
		)
		(fp_line
			(start 0.7874 -0.4064)
			(end 0.7874 0.4064)
			(stroke
				(width 0.1524)
				(type default)
			)
			(layer "F.SilkS")
		)
		(fp_line
			(start -0.7874 0.4064)
			(end -0.7874 -0.4064)
			(stroke
				(width 0.1524)
				(type default)
			)
			(layer "F.SilkS")
		)
		(fp_line
			(start -0.7874 -0.4064)
			(end 0.7874 -0.4064)
			(stroke
				(width 0.1524)
				(type default)
			)
			(layer "F.SilkS")
		)
		(fp_line
			(start 0.67945 0.3048)
			(end 0.120396 0.3048)
			(stroke
				(width 0.1)
				(type default)
			)
			(layer "F.Fab")
		)
		(fp_line
			(start 0.67945 -0.3048)
			(end 0.67945 0.3048)
			(stroke
				(width 0.1)
				(type default)
			)
			(layer "F.Fab")
		)
		(fp_line
			(start 0.12065 -0.2794)
			(end 0.12065 -0.3048)
			(stroke
				(width 0.1)
				(type default)
			)
			(layer "F.Fab")
		)
		(fp_line
			(start 0.12065 -0.3048)
			(end 0.67945 -0.3048)
			(stroke
				(width 0.1)
				(type default)
			)
			(layer "F.Fab")
		)
		(fp_line
			(start 0.120396 0.3048)
			(end 0.120396 0.2794)
			(stroke
				(width 0.1)
				(type default)
			)
			(layer "F.Fab")
		)
		(fp_line
			(start 0.120396 0.2794)
			(end -0.12065 0.2794)
			(stroke
				(width 0.1)
				(type default)
			)
			(layer "F.Fab")
		)
		(fp_line
			(start -0.12065 0.3048)
			(end -0.67945 0.3048)
			(stroke
				(width 0.1)
				(type default)
			)
			(layer "F.Fab")
		)
		(fp_line
			(start -0.12065 0.2794)
			(end -0.12065 0.3048)
			(stroke
				(width 0.1)
				(type default)
			)
			(layer "F.Fab")
		)
		(fp_line
			(start -0.12065 -0.2794)
			(end 0.12065 -0.2794)
			(stroke
				(width 0.1)
				(type default)
			)
			(layer "F.Fab")
		)
		(fp_line
			(start -0.12065 -0.305054)
			(end -0.12065 -0.2794)
			(stroke
				(width 0.1)
				(type default)
			)
			(layer "F.Fab")
		)
		(fp_line
			(start -0.67945 0.3048)
			(end -0.67945 -0.305054)
			(stroke
				(width 0.1)
				(type default)
			)
			(layer "F.Fab")
		)
		(fp_line
			(start -0.67945 -0.305054)
			(end -0.12065 -0.305054)
			(stroke
				(width 0.1)
				(type default)
			)
			(layer "F.Fab")
		)
		(pad "1" smd circle
			(at -0.40005 0 180)
			(size 0 0)
			(layers "F.Cu" "F.Mask" "F.Paste")
			(net "P3V3_AUX")
		)
		(pad "2" smd circle
			(at 0.40005 0 180)
			(size 0 0)
			(layers "F.Cu" "F.Mask" "F.Paste")
			(net "FM_SCM_PRSNT1_N")
		)
	)
)
